G04 ================== begin FILE IDENTIFICATION RECORD ==================*
G04 Layout Name:  12523-1.brd*
G04 Film Name:    L1*
G04 File Format:  Gerber RS274X*
G04 File Origin:  Cadence Allegro 16.2-s031*
G04 Origin Date:  Fri Oct 19 14:59:12 2012*
G04 *
G04 Layer:  VIA CLASS/TOP*
G04 Layer:  PIN/TOP*
G04 Layer:  ETCH/TOP*
G04 Layer:  DRAWING FORMAT/LAYER_PCB_STORY*
G04 Layer:  DRAWING FORMAT/LAYER_L1*
G04 *
G04 Offset:    (0.00 0.00)*
G04 Mirror:    No*
G04 Mode:      Positive*
G04 Rotation:  0*
G04 FullContactRelief:  No*
G04 UndefLineWidth:     6.00*
G04 ================== end FILE IDENTIFICATION RECORD ====================*
%FSLAX35Y35*MOIN*%
%IR0*IPPOS*OFA0.00000B0.00000*MIA0B0*SFA1.00000B1.00000*%
%AMMACRO26*
4,1,40,.017,-.013,
.017,.013,
.016939,.013695,
.016759,.014368,
.016464,.015,
.016064,.015571,
.015571,.016064,
.015,.016464,
.014368,.016759,
.013695,.016939,
.013,.017,
-.013,.017,
-.013695,.016939,
-.014368,.016759,
-.015,.016464,
-.015571,.016064,
-.016064,.015571,
-.016464,.015,
-.016759,.014368,
-.016939,.013695,
-.017,.013,
-.017,-.013,
-.016939,-.013695,
-.016759,-.014368,
-.016464,-.015,
-.016064,-.015571,
-.015571,-.016064,
-.015,-.016464,
-.014368,-.016759,
-.013695,-.016939,
-.013,-.017,
.013,-.017,
.013695,-.016939,
.014368,-.016759,
.015,-.016464,
.015571,-.016064,
.016064,-.015571,
.016464,-.015,
.016759,-.014368,
.016939,-.013695,
.017,-.013,
0.0*
%
%ADD26MACRO26*%
%ADD36R,.11X.055*%
%ADD10C,.01*%
%ADD41R,.074X.122*%
%AMMACRO11*
4,1,21,.062,.1775,
.092823,.174803,
.122709,.166795,
.15075,.15372,
.176095,.135973,
.197973,.114095,
.21572,.08875,
.228795,.060709,
.236803,.030823,
.2395,0.0,
.236803,-.030823,
.228795,-.060709,
.21572,-.08875,
.197973,-.114095,
.176095,-.135973,
.15075,-.15372,
.122709,-.166795,
.092823,-.174803,
.062,-.1775,
-.2395,-.1775,
-.2395,.1775,
.062,.1775,
0.0*
%
%ADD11MACRO11*%
%ADD34C,.032*%
%ADD40C,.053*%
%ADD18R,.197X.032*%
%ADD13C,.028*%
%ADD38C,.057*%
%ADD12R,.05X.05*%
%AMMACRO32*
4,1,40,.007,.011,
-.007,.011,
-.007695,.010939,
-.008368,.010759,
-.009,.010464,
-.009571,.010064,
-.010064,.009571,
-.010464,.009,
-.010759,.008368,
-.010939,.007695,
-.011,.007,
-.011,-.007,
-.010939,-.007695,
-.010759,-.008368,
-.010464,-.009,
-.010064,-.009571,
-.009571,-.010064,
-.009,-.010464,
-.008368,-.010759,
-.007695,-.010939,
-.007,-.011,
.007,-.011,
.007695,-.010939,
.008368,-.010759,
.009,-.010464,
.009571,-.010064,
.010064,-.009571,
.010464,-.009,
.010759,-.008368,
.010939,-.007695,
.011,-.007,
.011,.007,
.010939,.007695,
.010759,.008368,
.010464,.009,
.010064,.009571,
.009571,.010064,
.009,.010464,
.008368,.010759,
.007695,.010939,
.007,.011,
0.0*
%
%ADD32MACRO32*%
%AMMACRO24*
4,1,40,.011,-.007,
.011,.007,
.010939,.007695,
.010759,.008368,
.010464,.009,
.010064,.009571,
.009571,.010064,
.009,.010464,
.008368,.010759,
.007695,.010939,
.007,.011,
-.007,.011,
-.007695,.010939,
-.008368,.010759,
-.009,.010464,
-.009571,.010064,
-.010064,.009571,
-.010464,.009,
-.010759,.008368,
-.010939,.007695,
-.011,.007,
-.011,-.007,
-.010939,-.007695,
-.010759,-.008368,
-.010464,-.009,
-.010064,-.009571,
-.009571,-.010064,
-.009,-.010464,
-.008368,-.010759,
-.007695,-.010939,
-.007,-.011,
.007,-.011,
.007695,-.010939,
.008368,-.010759,
.009,-.010464,
.009571,-.010064,
.010064,-.009571,
.010464,-.009,
.010759,-.008368,
.010939,-.007695,
.011,-.007,
0.0*
%
%ADD24MACRO24*%
%AMMACRO27*
4,1,40,-.017,.013,
-.017,-.013,
-.016939,-.013695,
-.016759,-.014368,
-.016464,-.015,
-.016064,-.015571,
-.015571,-.016064,
-.015,-.016464,
-.014368,-.016759,
-.013695,-.016939,
-.013,-.017,
.013,-.017,
.013695,-.016939,
.014368,-.016759,
.015,-.016464,
.015571,-.016064,
.016064,-.015571,
.016464,-.015,
.016759,-.014368,
.016939,-.013695,
.017,-.013,
.017,.013,
.016939,.013695,
.016759,.014368,
.016464,.015,
.016064,.015571,
.015571,.016064,
.015,.016464,
.014368,.016759,
.013695,.016939,
.013,.017,
-.013,.017,
-.013695,.016939,
-.014368,.016759,
-.015,.016464,
-.015571,.016064,
-.016064,.015571,
-.016464,.015,
-.016759,.014368,
-.016939,.013695,
-.017,.013,
0.0*
%
%ADD27MACRO27*%
%AMMACRO33*
4,1,40,.007,.011,
-.007,.011,
-.007695,.010939,
-.008368,.010759,
-.009,.010464,
-.009571,.010064,
-.010064,.009571,
-.010464,.009,
-.010759,.008368,
-.010939,.007695,
-.011,.007,
-.011,-.007,
-.010939,-.007695,
-.010759,-.008368,
-.010464,-.009,
-.010064,-.009571,
-.009571,-.010064,
-.009,-.010464,
-.008368,-.010759,
-.007695,-.010939,
-.007,-.011,
.007,-.011,
.007695,-.010939,
.008368,-.010759,
.009,-.010464,
.009571,-.010064,
.010064,-.009571,
.010464,-.009,
.010759,-.008368,
.010939,-.007695,
.011,-.007,
.011,.007,
.010939,.007695,
.010759,.008368,
.010464,.009,
.010064,.009571,
.009571,.010064,
.009,.010464,
.008368,.010759,
.007695,.010939,
.007,.011,
0.0*
%
%ADD33MACRO33*%
%AMMACRO25*
4,1,40,.011,-.007,
.011,.007,
.010939,.007695,
.010759,.008368,
.010464,.009,
.010064,.009571,
.009571,.010064,
.009,.010464,
.008368,.010759,
.007695,.010939,
.007,.011,
-.007,.011,
-.007695,.010939,
-.008368,.010759,
-.009,.010464,
-.009571,.010064,
-.010064,.009571,
-.010464,.009,
-.010759,.008368,
-.010939,.007695,
-.011,.007,
-.011,-.007,
-.010939,-.007695,
-.010759,-.008368,
-.010464,-.009,
-.010064,-.009571,
-.009571,-.010064,
-.009,-.010464,
-.008368,-.010759,
-.007695,-.010939,
-.007,-.011,
.007,-.011,
.007695,-.010939,
.008368,-.010759,
.009,-.010464,
.009571,-.010064,
.010064,-.009571,
.010464,-.009,
.010759,-.008368,
.010939,-.007695,
.011,-.007,
0.0*
%
%ADD25MACRO25*%
%AMMACRO28*
4,1,40,-.017,.013,
-.017,-.013,
-.016939,-.013695,
-.016759,-.014368,
-.016464,-.015,
-.016064,-.015571,
-.015571,-.016064,
-.015,-.016464,
-.014368,-.016759,
-.013695,-.016939,
-.013,-.017,
.013,-.017,
.013695,-.016939,
.014368,-.016759,
.015,-.016464,
.015571,-.016064,
.016064,-.015571,
.016464,-.015,
.016759,-.014368,
.016939,-.013695,
.017,-.013,
.017,.013,
.016939,.013695,
.016759,.014368,
.016464,.015,
.016064,.015571,
.015571,.016064,
.015,.016464,
.014368,.016759,
.013695,.016939,
.013,.017,
-.013,.017,
-.013695,.016939,
-.014368,.016759,
-.015,.016464,
-.015571,.016064,
-.016064,.015571,
-.016464,.015,
-.016759,.014368,
-.016939,.013695,
-.017,.013,
0.0*
%
%ADD28MACRO28*%
%ADD14R,.001X.001*%
%ADD19R,.016X.06*%
%ADD16R,.055X.045*%
%ADD17R,.248X.165*%
%ADD15R,.248X.372*%
%ADD35O,.827X.355*%
%AMMACRO39*
4,1,40,.007,.0225,
.008389,.022378,
.009736,.022018,
.011,.021428,
.012142,.020628,
.013128,.019642,
.013928,.0185,
.014518,.017236,
.014878,.015889,
.015,.0145,
.015,-.0145,
.014878,-.015889,
.014518,-.017236,
.013928,-.0185,
.013128,-.019642,
.012142,-.020628,
.011,-.021428,
.009736,-.022018,
.008389,-.022378,
.007,-.0225,
-.007,-.0225,
-.008389,-.022378,
-.009736,-.022018,
-.011,-.021428,
-.012142,-.020628,
-.013128,-.019642,
-.013928,-.0185,
-.014518,-.017236,
-.014878,-.015889,
-.015,-.0145,
-.015,.0145,
-.014878,.015889,
-.014518,.017236,
-.013928,.0185,
-.013128,.019642,
-.012142,.020628,
-.011,.021428,
-.009736,.022018,
-.008389,.022378,
-.007,.0225,
.007,.0225,
0.0*
%
%ADD39MACRO39*%
%ADD37R,.095X.09*%
%AMMACRO31*
4,1,40,-.008,-.012,
.008,-.012,
.008695,-.011939,
.009368,-.011759,
.01,-.011464,
.010571,-.011064,
.011064,-.010571,
.011464,-.01,
.011759,-.009368,
.011939,-.008695,
.012,-.008,
.012,.008,
.011939,.008695,
.011759,.009368,
.011464,.01,
.011064,.010571,
.010571,.011064,
.01,.011464,
.009368,.011759,
.008695,.011939,
.008,.012,
-.008,.012,
-.008695,.011939,
-.009368,.011759,
-.01,.011464,
-.010571,.011064,
-.011064,.010571,
-.011464,.01,
-.011759,.009368,
-.011939,.008695,
-.012,.008,
-.012,-.008,
-.011939,-.008695,
-.011759,-.009368,
-.011464,-.01,
-.011064,-.010571,
-.010571,-.011064,
-.01,-.011464,
-.009368,-.011759,
-.008695,-.011939,
-.008,-.012,
0.0*
%
%ADD31MACRO31*%
%AMMACRO20*
4,1,40,-.007,-.011,
.007,-.011,
.007695,-.010939,
.008368,-.010759,
.009,-.010464,
.009571,-.010064,
.010064,-.009571,
.010464,-.009,
.010759,-.008368,
.010939,-.007695,
.011,-.007,
.011,.007,
.010939,.007695,
.010759,.008368,
.010464,.009,
.010064,.009571,
.009571,.010064,
.009,.010464,
.008368,.010759,
.007695,.010939,
.007,.011,
-.007,.011,
-.007695,.010939,
-.008368,.010759,
-.009,.010464,
-.009571,.010064,
-.010064,.009571,
-.010464,.009,
-.010759,.008368,
-.010939,.007695,
-.011,.007,
-.011,-.007,
-.010939,-.007695,
-.010759,-.008368,
-.010464,-.009,
-.010064,-.009571,
-.009571,-.010064,
-.009,-.010464,
-.008368,-.010759,
-.007695,-.010939,
-.007,-.011,
0.0*
%
%ADD20MACRO20*%
%AMMACRO22*
4,1,40,-.011,.007,
-.011,-.007,
-.010939,-.007695,
-.010759,-.008368,
-.010464,-.009,
-.010064,-.009571,
-.009571,-.010064,
-.009,-.010464,
-.008368,-.010759,
-.007695,-.010939,
-.007,-.011,
.007,-.011,
.007695,-.010939,
.008368,-.010759,
.009,-.010464,
.009571,-.010064,
.010064,-.009571,
.010464,-.009,
.010759,-.008368,
.010939,-.007695,
.011,-.007,
.011,.007,
.010939,.007695,
.010759,.008368,
.010464,.009,
.010064,.009571,
.009571,.010064,
.009,.010464,
.008368,.010759,
.007695,.010939,
.007,.011,
-.007,.011,
-.007695,.010939,
-.008368,.010759,
-.009,.010464,
-.009571,.010064,
-.010064,.009571,
-.010464,.009,
-.010759,.008368,
-.010939,.007695,
-.011,.007,
0.0*
%
%ADD22MACRO22*%
%AMMACRO29*
4,1,40,.017,-.013,
.017,.013,
.016939,.013695,
.016759,.014368,
.016464,.015,
.016064,.015571,
.015571,.016064,
.015,.016464,
.014368,.016759,
.013695,.016939,
.013,.017,
-.013,.017,
-.013695,.016939,
-.014368,.016759,
-.015,.016464,
-.015571,.016064,
-.016064,.015571,
-.016464,.015,
-.016759,.014368,
-.016939,.013695,
-.017,.013,
-.017,-.013,
-.016939,-.013695,
-.016759,-.014368,
-.016464,-.015,
-.016064,-.015571,
-.015571,-.016064,
-.015,-.016464,
-.014368,-.016759,
-.013695,-.016939,
-.013,-.017,
.013,-.017,
.013695,-.016939,
.014368,-.016759,
.015,-.016464,
.015571,-.016064,
.016064,-.015571,
.016464,-.015,
.016759,-.014368,
.016939,-.013695,
.017,-.013,
0.0*
%
%ADD29MACRO29*%
%AMMACRO30*
4,1,40,-.008,-.012,
.008,-.012,
.008695,-.011939,
.009368,-.011759,
.01,-.011464,
.010571,-.011064,
.011064,-.010571,
.011464,-.01,
.011759,-.009368,
.011939,-.008695,
.012,-.008,
.012,.008,
.011939,.008695,
.011759,.009368,
.011464,.01,
.011064,.010571,
.010571,.011064,
.01,.011464,
.009368,.011759,
.008695,.011939,
.008,.012,
-.008,.012,
-.008695,.011939,
-.009368,.011759,
-.01,.011464,
-.010571,.011064,
-.011064,.010571,
-.011464,.01,
-.011759,.009368,
-.011939,.008695,
-.012,.008,
-.012,-.008,
-.011939,-.008695,
-.011759,-.009368,
-.011464,-.01,
-.011064,-.010571,
-.010571,-.011064,
-.01,-.011464,
-.009368,-.011759,
-.008695,-.011939,
-.008,-.012,
0.0*
%
%ADD30MACRO30*%
%AMMACRO21*
4,1,40,-.007,-.011,
.007,-.011,
.007695,-.010939,
.008368,-.010759,
.009,-.010464,
.009571,-.010064,
.010064,-.009571,
.010464,-.009,
.010759,-.008368,
.010939,-.007695,
.011,-.007,
.011,.007,
.010939,.007695,
.010759,.008368,
.010464,.009,
.010064,.009571,
.009571,.010064,
.009,.010464,
.008368,.010759,
.007695,.010939,
.007,.011,
-.007,.011,
-.007695,.010939,
-.008368,.010759,
-.009,.010464,
-.009571,.010064,
-.010064,.009571,
-.010464,.009,
-.010759,.008368,
-.010939,.007695,
-.011,.007,
-.011,-.007,
-.010939,-.007695,
-.010759,-.008368,
-.010464,-.009,
-.010064,-.009571,
-.009571,-.010064,
-.009,-.010464,
-.008368,-.010759,
-.007695,-.010939,
-.007,-.011,
0.0*
%
%ADD21MACRO21*%
%AMMACRO23*
4,1,40,-.011,.007,
-.011,-.007,
-.010939,-.007695,
-.010759,-.008368,
-.010464,-.009,
-.010064,-.009571,
-.009571,-.010064,
-.009,-.010464,
-.008368,-.010759,
-.007695,-.010939,
-.007,-.011,
.007,-.011,
.007695,-.010939,
.008368,-.010759,
.009,-.010464,
.009571,-.010064,
.010064,-.009571,
.010464,-.009,
.010759,-.008368,
.010939,-.007695,
.011,-.007,
.011,.007,
.010939,.007695,
.010759,.008368,
.010464,.009,
.010064,.009571,
.009571,.010064,
.009,.010464,
.008368,.010759,
.007695,.010939,
.007,.011,
-.007,.011,
-.007695,.010939,
-.008368,.010759,
-.009,.010464,
-.009571,.010064,
-.010064,.009571,
-.010464,.009,
-.010759,.008368,
-.010939,.007695,
-.011,.007,
0.0*
%
%ADD23MACRO23*%
%ADD42C,.02*%
%ADD43C,.03*%
%ADD44C,.04*%
%ADD45C,.014*%
%ADD46C,.015*%
%ADD47C,.006*%
%ADD48C,.0055*%
%ADD50C,.08104*%
%ADD49C,.05806*%
%ADD51R,.015X.015*%
%ADD52C,.18206*%
G75*
%LPD*%
G75*
G36*
G01X624773Y68500D02*
X626297Y70024D01*
X629112D01*
X631594D01*
X632554Y69064D01*
X636443D01*
X636686Y69307D01*
G02X637369Y69024I283J-283D01*
G01Y4080D01*
X636492Y3203D01*
X4381D01*
X3000Y4584D01*
Y77000D01*
X5500Y79500D01*
X37000D01*
X54000Y62500D01*
X548000D01*
X581000Y95500D01*
X607500D01*
X613000Y90000D01*
Y73000D01*
X614500Y71500D01*
Y69000D01*
X615000Y68500D01*
X624773D01*
G37*
G36*
G01X554436Y184936D02*
X554500Y185000D01*
X556000D01*
X568000Y197000D01*
X605500D01*
X608000Y194500D01*
Y162000D01*
X589000Y143000D01*
Y111500D01*
X592000Y108500D01*
X611000D01*
X622000Y97500D01*
Y76000D01*
X621500Y75500D01*
X615500D01*
X615000Y76000D01*
Y91500D01*
X608500Y98000D01*
X580500D01*
X546936Y64436D01*
X56500D01*
X37936Y83000D01*
X5500D01*
X3000Y85500D01*
Y110834D01*
X-921Y114755D01*
X-30850D01*
X-30866Y114772D01*
X-32938D01*
X-33302Y115136D01*
Y151236D01*
X-32642Y151896D01*
X-12594D01*
X-12326Y152164D01*
Y154539D01*
X-12645Y154858D01*
X-33024D01*
X-33302Y155136D01*
Y191436D01*
X-32778Y191960D01*
X409040D01*
X416064Y184936D01*
X554436D01*
G37*
G36*
G01X417564Y187936D02*
X410564Y194936D01*
X-32902D01*
X-33302Y195336D01*
Y231336D01*
X-32702Y231936D01*
X-12538D01*
X-12366Y232108D01*
Y234653D01*
X-12575Y234862D01*
X-32628D01*
X-33202Y235436D01*
Y271336D01*
X-32609Y271929D01*
X-12610D01*
X-12463Y272076D01*
Y274708D01*
X-12616Y274861D01*
X-32727D01*
X-33202Y275336D01*
Y288382D01*
X-32585Y288999D01*
X814D01*
X22251Y310436D01*
X96398D01*
X110285Y296549D01*
X466021D01*
X532054Y230516D01*
X534338D01*
X534340Y230514D01*
X544000D01*
Y230500D01*
X553500D01*
X562000Y222000D01*
Y196000D01*
X553936Y187936D01*
X417564D01*
G37*
G36*
G01X-1002Y314209D02*
X-9525Y305686D01*
X-31054D01*
X-31296Y305928D01*
Y308663D01*
X-31198Y308761D01*
X-30956D01*
X-30955Y308760D01*
X-17679D01*
X-17599Y308840D01*
Y310498D01*
X-17704Y310603D01*
X-31124D01*
X-31296Y310775D01*
Y313350D01*
X-31002Y313644D01*
X-17783D01*
X-17782Y313643D01*
X-11903D01*
X-7286Y318260D01*
X-1770D01*
X-1002Y317492D01*
Y314209D01*
G37*
G36*
G01X605131Y291780D02*
X609674Y287238D01*
Y271792D01*
G02X608991Y271509I-400J0D01*
G01X605500Y275000D01*
X557000D01*
X555500Y273500D01*
X535115D01*
X479241Y329374D01*
X140292D01*
X94980Y374686D01*
X82779D01*
X82723Y374736D01*
G03X82276Y375054I-1724J-1950D01*
G01X82252Y375067D01*
X74259Y383060D01*
Y391741D01*
X68564Y397436D01*
X49898D01*
X47898Y395436D01*
Y391936D01*
X47398Y391436D01*
X43898D01*
X42774Y390312D01*
X34714D01*
X33991Y389589D01*
Y385309D01*
X35514Y383786D01*
X39327D01*
X39803Y383310D01*
Y378360D01*
X39111Y377668D01*
X34113D01*
X29963Y381818D01*
X26153D01*
X24676Y380340D01*
Y374973D01*
X17105Y367402D01*
X17110Y367397D01*
Y363523D01*
X-572Y345841D01*
X-7430D01*
X-10102Y348513D01*
Y361936D01*
X-9602Y362436D01*
X-1102D01*
X3398Y366936D01*
Y467936D01*
X4898Y469436D01*
X635898D01*
X637261Y468073D01*
Y388090D01*
X633197Y385366D01*
X629500D01*
X628000Y386866D01*
Y404500D01*
X623750Y408750D01*
Y415750D01*
X621500Y418000D01*
X609000D01*
X606898Y415898D01*
Y397936D01*
X604398Y395436D01*
X532798D01*
X523798Y386436D01*
Y338998D01*
X523789Y338968D01*
G03X523685Y338484I2480J-786D01*
G01X523677Y338415D01*
X518131Y332869D01*
Y332077D01*
X518114Y332039D01*
G03Y329961I2386J-1039D01*
G01X518131Y329923D01*
Y308869D01*
X526000Y301000D01*
Y291500D01*
X526463Y291037D01*
X526478Y291002D01*
G03X527506Y289974I1833J805D01*
G01X527541Y289959D01*
X528000Y289500D01*
X538500D01*
X540780Y291780D01*
X605131D01*
G37*
G36*
G01X46931Y336500D02*
X42445Y340986D01*
X20614D01*
X17293Y344307D01*
Y351626D01*
X24243Y358576D01*
X29901D01*
X32545Y361220D01*
Y363711D01*
X33729Y364895D01*
X39665D01*
X40289Y364271D01*
Y352705D01*
X40603Y352391D01*
Y352390D01*
X47059Y345934D01*
X47987D01*
X48000Y345932D01*
G03X48650I325J2582D01*
G01X48663Y345934D01*
X58809D01*
X60500Y347625D01*
Y360500D01*
X61000Y361000D01*
X63000D01*
X63425Y360575D01*
Y358290D01*
X64469Y357246D01*
X67848D01*
X69075Y358473D01*
Y360313D01*
X70262Y361500D01*
X97000D01*
X119875Y338625D01*
Y337226D01*
X119149Y336500D01*
X46931D01*
G37*
G36*
G01X594187Y130560D02*
G03X598860Y145822I6522J6349D01*
G02X598496Y146496I-81J392D01*
G01X613000Y161000D01*
Y267500D01*
X612626Y267874D01*
Y288462D01*
X606355Y294734D01*
X540750D01*
Y300250D01*
X546500Y306000D01*
Y313915D01*
Y313918D01*
G03Y314082I-2600J82D01*
G01Y314085D01*
Y323000D01*
X548500Y325000D01*
X614000D01*
X614064Y324936D01*
X621898D01*
X627398Y330436D01*
Y347353D01*
X628166Y348121D01*
X631099D01*
X637369Y343929D01*
Y321500D01*
X636369Y320500D01*
X622000D01*
X617500Y316000D01*
Y133000D01*
X621500Y129000D01*
X635500D01*
X637369Y127131D01*
Y75035D01*
G02X636686Y74752I-400J0D01*
G01X636474Y74964D01*
X632430D01*
X630966Y73500D01*
X626000D01*
X624000Y75500D01*
Y98000D01*
X611500Y110500D01*
X595000D01*
X593500Y112000D01*
Y130281D01*
G02X594187Y130560I400J0D01*
G37*
G36*
G01X548264Y328236D02*
X547500Y329000D01*
Y334500D01*
X548000Y335000D01*
X594778D01*
X594804Y334993D01*
G03X596196I696J2507D01*
G01X596222Y335000D01*
X599278D01*
X599304Y334993D01*
G03X600696I696J2507D01*
G01X600722Y335000D01*
X612000D01*
X613598Y336598D01*
Y350436D01*
X613896Y350734D01*
X624300D01*
X624598Y350436D01*
Y331736D01*
X621098Y328236D01*
X548264D01*
G37*
G36*
G01X530932Y337202D02*
X528147Y339987D01*
X528146Y339988D01*
G03X528073Y340061I-1876J-1803D01*
G01X528072Y340062D01*
X527798Y340336D01*
Y384936D01*
X534398Y391536D01*
X609598D01*
X610098Y391036D01*
Y381686D01*
X596348D01*
X594598Y383436D01*
X540598D01*
X536298Y379136D01*
Y334500D01*
X535365Y333567D01*
X533000D01*
X532500Y334067D01*
Y335500D01*
X532439Y335561D01*
X532437Y335641D01*
G03X531002Y337195I-1601J-39D01*
G01X530932Y337202D01*
G37*
G36*
G01X626500Y401500D02*
Y383500D01*
X625000Y382000D01*
X615000D01*
X614500Y382500D01*
Y393500D01*
X610500Y397500D01*
Y404000D01*
X611500Y405000D01*
X623000D01*
X626500Y401500D01*
G37*
G36*
G01X610198Y350436D02*
X611598Y349036D01*
Y339000D01*
X609348Y336750D01*
X593712D01*
X592462Y338000D01*
Y348962D01*
X593936Y350436D01*
X610198D01*
G37*
%LPC*%
G75*
G36*
G01X594749Y79070D02*
X594629Y79116D01*
X594422Y78909D01*
G03X594705Y78226I283J-283D01*
G01X600242D01*
X600284Y78248D01*
G02X598157Y74867I1724J-3444D01*
G03X597757Y75274I-400J7D01*
G01X585076D01*
X585016Y75187D01*
G02X583700Y74498I-1316J912D01*
G01X582300D01*
G02X580698Y76100I0J1602D01*
G01Y77500D01*
G02X581049Y78500I1602J-1D01*
G02X580698Y79500I1251J1001D01*
G01Y80900D01*
G02X582300Y82502I1602J0D01*
G01X583700D01*
G02X585283Y81146I0J-1602D01*
G01X585309Y80976D01*
X592313D01*
X592541Y81204D01*
X592495Y81324D01*
G02X594749Y79070I3607J1353D01*
G37*
G36*
G01X583221Y68847D02*
X592760D01*
X592818Y68942D01*
G02X592667Y65186I3284J-2013D01*
G01X592652Y65215D01*
X592488Y65378D01*
X592329Y65219D01*
X583570D01*
X582817Y64466D01*
X579687D01*
X578791Y65362D01*
Y68494D01*
X579602Y69305D01*
X582763D01*
X583221Y68847D01*
G37*
G36*
G01X25118Y219438D02*
X21181D01*
G02X14242Y226378I1J6940D01*
G01Y246063D01*
G02X21181Y253002I6939J0D01*
G01X25118D01*
G02X32058Y246063I1J-6939D01*
G01Y226378D01*
G02X25118Y219438I-6940J0D01*
G37*
G54D50*
X570709Y161889D03*
X580709D03*
X570709Y191889D03*
X580709D03*
X570709Y181889D03*
X580709D03*
X570709Y171889D03*
X580709D03*
X590709Y161889D03*
X600709D03*
X590709Y191889D03*
X600709D03*
X590709Y181889D03*
X600709D03*
X590709Y171889D03*
X600709D03*
G54D49*
X599055Y59055D03*
Y90551D03*
G54D51*
X539750Y277250D03*
X544750D03*
X39250Y393250D03*
X43250Y396250D03*
G54D52*
X600709Y311909D03*
%LPD*%
G75*
G54D10*
X-23621Y15748D03*
Y937008D03*
X599055Y59055D03*
Y90551D03*
X600709Y136909D03*
Y311909D03*
X1312285Y15747D03*
G54D20*
X33508Y374132D03*
Y368932D03*
X38598Y337936D03*
Y333436D03*
X69550Y378236D03*
X69547Y373979D03*
X69498Y369470D03*
X537733Y263971D03*
Y268971D03*
X526200Y326000D03*
X533636Y326402D03*
X533536Y330602D03*
X533636Y322102D03*
G54D11*
X23957Y61023D03*
Y415354D03*
G54D21*
X30108Y374132D03*
Y368932D03*
X35198Y337936D03*
Y333436D03*
X66150Y378236D03*
X66147Y373979D03*
X66098Y369470D03*
X534333Y263971D03*
Y268971D03*
X522800Y326000D03*
X530236Y326402D03*
X530136Y330602D03*
X530236Y322102D03*
G54D30*
X41309Y387463D03*
G54D12*
X-23622Y62794D03*
Y916269D03*
X1297695Y58466D03*
G54D22*
X43072Y365847D03*
X43159Y373885D03*
X55352Y387374D03*
X60052Y387292D03*
X51094Y387325D03*
X538000Y293300D03*
X583000Y76800D03*
G54D31*
X41309Y391063D03*
G54D13*
X6419Y116482D03*
X-3350Y117504D03*
X6419Y126482D03*
X-3581D03*
X6419Y136482D03*
X-3581D03*
X6419Y146482D03*
X-3581D03*
X6419Y156482D03*
X-3581D03*
X-2602Y206936D03*
X7398D03*
X-2602Y216936D03*
X7398D03*
X6419Y166482D03*
X-3581D03*
Y176482D03*
X6419D03*
X-2602Y226936D03*
X7398D03*
X-2602Y246936D03*
X7398D03*
X-2602Y236936D03*
X7398D03*
Y256936D03*
X-2602D03*
Y266936D03*
X7398D03*
Y276936D03*
X-2602D03*
X7398Y286936D03*
X3398Y326936D03*
X-2948Y302202D03*
X-2602Y316436D03*
X-7102Y327202D03*
X-6940Y316247D03*
X2334Y318654D03*
X1494Y343705D03*
X5694D03*
X-6602Y347202D03*
X-7102Y337202D03*
X-6602Y357202D03*
X6898Y387436D03*
X6398Y369936D03*
X6898Y445436D03*
Y465436D03*
X16419Y6482D03*
Y26482D03*
X36419Y6482D03*
Y26482D03*
X56419Y46482D03*
X16419Y86482D03*
X36419D03*
X56419Y66482D03*
Y86482D03*
X26419Y116482D03*
X16419D03*
X26419Y126482D03*
X16419D03*
X26419Y136482D03*
X16419D03*
X26419Y146482D03*
X16419D03*
X26419Y156482D03*
X16419D03*
X36419Y126482D03*
X16419Y106482D03*
X36419D03*
Y146482D03*
X56419Y126482D03*
Y106482D03*
Y146482D03*
X27398Y206936D03*
X17398D03*
X27398Y216936D03*
X17398D03*
X26419Y186482D03*
X16419D03*
X26419Y166482D03*
X16419D03*
Y176482D03*
X26419D03*
X36419Y186482D03*
Y166482D03*
X56419Y186482D03*
Y166482D03*
X57398Y206936D03*
X37398D03*
X17398Y256936D03*
X27398D03*
Y266936D03*
X17398D03*
X57398Y226936D03*
X36769D03*
X57398Y246936D03*
Y266936D03*
X36769Y246936D03*
X37398Y266936D03*
X17398Y276936D03*
X27398Y286936D03*
X17398D03*
X27398Y276936D03*
X10000Y332000D03*
X57398Y286936D03*
X37398D03*
X64398Y304436D03*
X30923Y335665D03*
X25500Y353000D03*
X25000Y343000D03*
X33986Y362933D03*
X26723Y335665D03*
X22000Y374500D03*
X34898Y344936D03*
X57398Y348682D03*
X52705Y348626D03*
X48325Y348514D03*
X62398Y338436D03*
X37500Y386500D03*
X22000Y387500D03*
X61898Y358936D03*
X43038Y353675D03*
X28182Y364061D03*
Y379003D03*
X43072Y360525D03*
X43159Y382607D03*
X62000Y442500D03*
X60052Y394674D03*
X35830Y442464D03*
X55352Y394674D03*
X51094Y394478D03*
X55500Y417000D03*
X19898Y465436D03*
X39898D03*
X76419Y46482D03*
X116419D03*
X96419D03*
X76419Y66482D03*
Y86482D03*
X116419Y66482D03*
X96419D03*
X116419Y86482D03*
X96419D03*
X76419Y126482D03*
Y106482D03*
Y146482D03*
X116419Y126482D03*
Y106482D03*
X96419Y126482D03*
Y106482D03*
X116419Y146482D03*
X96419D03*
X76419Y186482D03*
Y166482D03*
X77398Y206936D03*
X116419Y186482D03*
Y166482D03*
X96419Y186482D03*
Y166482D03*
X117398Y206936D03*
X97398D03*
X77398Y226936D03*
Y246936D03*
Y266936D03*
X117398Y226936D03*
X97398D03*
X117398Y246936D03*
X97398D03*
Y266936D03*
X116398D03*
X77398Y286936D03*
X86398Y303936D03*
X97398Y286936D03*
X116398D03*
X77898Y338436D03*
X78398Y358436D03*
X115330Y337964D03*
X96398Y337936D03*
X115330Y377964D03*
Y357964D03*
X95330Y377964D03*
Y357964D03*
X74803Y369471D03*
X81000Y372786D03*
X66041Y359891D03*
X66100Y383508D03*
X105330Y442964D03*
X85330D03*
X75500Y417500D03*
X115330Y417964D03*
X95330D03*
X91500Y465500D03*
X117500D03*
X67830Y465464D03*
X136419Y6482D03*
Y46482D03*
X176419Y6482D03*
Y26482D03*
X156419Y6482D03*
Y26482D03*
X176419Y46482D03*
X156419D03*
X136419Y66482D03*
Y86482D03*
X176419Y66482D03*
X156419D03*
X176419Y86482D03*
X156419D03*
X136419Y126482D03*
Y106482D03*
Y146482D03*
X176419Y126482D03*
Y106482D03*
X156419Y126482D03*
Y106482D03*
X176419Y146482D03*
X156419D03*
X136419Y186482D03*
Y166482D03*
X137398Y206936D03*
X176419Y186482D03*
Y166482D03*
X156419Y186482D03*
Y166482D03*
X177398Y206436D03*
X157398Y206936D03*
X137398Y226936D03*
Y246936D03*
Y266936D03*
X177398Y226936D03*
X157398D03*
X177398Y246936D03*
Y266936D03*
X157398Y246936D03*
Y266936D03*
X137398Y286936D03*
X177398D03*
X157398D03*
X135063Y304219D03*
X176762Y319444D03*
X135330Y337964D03*
Y377964D03*
Y357964D03*
X175330Y337964D03*
X155330D03*
X175330Y377964D03*
Y357964D03*
X155330Y377964D03*
Y357964D03*
X132000Y442500D03*
X135330Y417964D03*
X175500Y442000D03*
X175330Y417964D03*
X155000Y442000D03*
X155330Y417964D03*
X139898Y465436D03*
X159898D03*
X196419Y6482D03*
Y26482D03*
Y46482D03*
X236419Y6482D03*
Y26482D03*
X216419Y6482D03*
Y26482D03*
X236419Y46482D03*
X216419D03*
X196419Y66482D03*
Y86482D03*
X236419Y66482D03*
X216419D03*
X236419Y86482D03*
X216419D03*
X196419Y126482D03*
Y106482D03*
Y146482D03*
X236419Y126482D03*
Y106482D03*
X216419Y126482D03*
Y106482D03*
X236419Y146482D03*
X216419D03*
X196419Y186482D03*
Y166482D03*
X197398Y206436D03*
X236419Y186482D03*
Y166482D03*
X216419Y186482D03*
Y166482D03*
X217398Y206436D03*
X197398Y226936D03*
Y246936D03*
Y266936D03*
X217398Y226936D03*
Y246936D03*
Y266936D03*
X197398Y286936D03*
X217398D03*
X228716Y315094D03*
X196289Y302044D03*
X195330Y337964D03*
Y377964D03*
Y357964D03*
X235330Y337964D03*
X215330D03*
X235330Y377964D03*
Y357964D03*
X215330Y377964D03*
Y357964D03*
X196000Y442500D03*
X195330Y417964D03*
X235830Y442464D03*
X235330Y417964D03*
X215830Y442464D03*
X215330Y417964D03*
X179898Y465436D03*
X219898D03*
X199898D03*
X256419Y6482D03*
Y26482D03*
X276419Y6482D03*
Y26482D03*
X256419Y46482D03*
X276419D03*
X256419Y66482D03*
X273500Y66500D03*
X256419Y86482D03*
X274500Y86500D03*
X256419Y126482D03*
X276419D03*
X256419Y106482D03*
X274500Y106500D03*
X256419Y146482D03*
X276419D03*
X237398Y206436D03*
X256419Y186482D03*
X275500Y186500D03*
X251500Y166500D03*
X276419Y166482D03*
X257398Y206436D03*
X277398D03*
X237398Y226936D03*
Y246936D03*
Y266936D03*
X257398Y226936D03*
X277398D03*
X257398Y246936D03*
X277398D03*
X257398Y266936D03*
X277398D03*
X237398Y286936D03*
X257398D03*
X279398D03*
X264680Y317269D03*
X255330Y337964D03*
X275330D03*
X255330Y377964D03*
X275330D03*
X255330Y357964D03*
X275330D03*
X255830Y442464D03*
X275830D03*
X255330Y417964D03*
X275330D03*
X239898Y465436D03*
X279898D03*
X259898D03*
X296419Y6482D03*
Y26482D03*
Y46482D03*
X316419Y6482D03*
Y26482D03*
X336419Y6482D03*
Y26482D03*
X316419Y46482D03*
X336419D03*
X302000Y67000D03*
X301000Y86500D03*
X316419Y66482D03*
X336419D03*
X316419Y86482D03*
X336419D03*
X296419Y126482D03*
X300000Y106500D03*
X296419Y146482D03*
X316419Y126482D03*
X336419D03*
X316419Y106482D03*
X336419D03*
X316419Y146482D03*
X336419D03*
X296419Y186482D03*
X295500Y169000D03*
X297398Y206436D03*
X317500Y186500D03*
X336419Y186482D03*
X317000Y166500D03*
X338500Y166000D03*
X317398Y206436D03*
X337398D03*
X297398Y226936D03*
Y246936D03*
Y266936D03*
X317398Y226936D03*
X337398D03*
X317398Y246936D03*
X337398D03*
X317398Y266936D03*
X337398D03*
X300398Y286936D03*
X317398D03*
X337398D03*
X310990Y310744D03*
X295330Y337964D03*
Y377964D03*
Y357964D03*
X315330Y337964D03*
X335330D03*
X315330Y377964D03*
X335330D03*
X315330Y357964D03*
X335330D03*
X295830Y442464D03*
X295330Y417964D03*
X315830Y442464D03*
X335830D03*
X315330Y417964D03*
X335330D03*
X299898Y465436D03*
X339898D03*
X319898D03*
X356419Y6482D03*
Y26482D03*
Y46482D03*
X376419Y6482D03*
Y26482D03*
X396419Y6482D03*
Y26482D03*
X376419Y46482D03*
X396419D03*
X356419Y66482D03*
Y86482D03*
X376419Y66482D03*
X396419D03*
X376419Y86482D03*
X396419D03*
X356419Y126482D03*
Y106482D03*
Y146482D03*
X376419Y126482D03*
X396419D03*
X376419Y106482D03*
X396419D03*
X376419Y146482D03*
X396419D03*
X357500Y186500D03*
X354500Y166500D03*
X357398Y206436D03*
X376419Y186482D03*
X396419D03*
X380000Y166500D03*
X396419Y166482D03*
X377398Y206436D03*
X397398D03*
X357398Y226936D03*
Y246936D03*
Y266936D03*
X377398Y226936D03*
X397398D03*
X377398Y246936D03*
X397398D03*
X377398Y266936D03*
X397398D03*
X357398Y286936D03*
X377398D03*
X397398D03*
X358093Y312919D03*
X401561Y306394D03*
X355330Y337964D03*
Y377964D03*
Y357964D03*
X375330Y337964D03*
X395330D03*
X375330Y377964D03*
X395330D03*
X375330Y357964D03*
X395330D03*
X355830Y442464D03*
X355330Y417964D03*
X375830Y442464D03*
X395830D03*
X375330Y417964D03*
X395330D03*
X399898Y465436D03*
X379898D03*
X359898D03*
X416419Y6482D03*
Y26482D03*
X436419Y6482D03*
X416419Y46482D03*
X436419D03*
X456419D03*
X416419Y66482D03*
X436419D03*
X456419D03*
X416419Y86482D03*
X436419D03*
X456419D03*
X416419Y126482D03*
X436419D03*
X456419D03*
X416419Y106482D03*
X436419D03*
X456419D03*
X416419Y146482D03*
X436419D03*
X456419D03*
X416500Y166000D03*
X417519Y174482D03*
Y170282D03*
X425919D03*
X421719D03*
Y174482D03*
X431100Y174500D03*
Y170300D03*
X439500D03*
Y174500D03*
X435300Y170300D03*
Y174500D03*
X444100D03*
Y170300D03*
X452500D03*
Y174500D03*
X448300Y170300D03*
Y174500D03*
X457100Y175000D03*
Y170800D03*
X461300D03*
Y175000D03*
X418300Y197500D03*
Y201700D03*
X422500D03*
X426700D03*
X422500Y197500D03*
X426700D03*
X431300D03*
Y201700D03*
X435500D03*
X439700D03*
X435500Y197500D03*
X439700D03*
X444800D03*
Y201700D03*
X449000D03*
X453200D03*
X449000Y197500D03*
X453200D03*
X457800D03*
Y201700D03*
X462000D03*
Y197500D03*
X425919Y174482D03*
X436500Y166000D03*
X456500Y166500D03*
X417398Y206436D03*
X437398D03*
X457398D03*
X417398Y226936D03*
X437398D03*
X457398D03*
X417398Y246936D03*
X437398D03*
X457398D03*
X437398Y266936D03*
X457398D03*
X418398D03*
X437398Y286936D03*
X457398D03*
X418398D03*
X463259Y299869D03*
X439407Y308569D03*
X439585Y321619D03*
X415330Y337964D03*
X435398Y338436D03*
X455398D03*
X415330Y377964D03*
Y357964D03*
X435398Y358436D03*
Y378436D03*
X455398Y358436D03*
Y378436D03*
X435830Y442464D03*
X455830D03*
X435330Y417964D03*
X455330D03*
X415830Y442464D03*
X415330Y417964D03*
X459898Y465436D03*
X439898D03*
X419898D03*
X516419Y6482D03*
X476419Y46482D03*
X496419D03*
X516419D03*
Y66482D03*
X476419D03*
X496419D03*
X516419Y86482D03*
X496419D03*
X476419D03*
Y126482D03*
X516419D03*
X496419D03*
X516419Y106482D03*
X496419D03*
X476419D03*
X485443Y160670D03*
X481243D03*
X493843D03*
X489643D03*
X476419Y146482D03*
X516419D03*
X496419D03*
X519221Y160912D03*
X510821D03*
X506621D03*
X515021D03*
X465500Y170800D03*
Y175000D03*
X466200Y201700D03*
Y197500D03*
X485443Y164870D03*
X481243D03*
X493843D03*
X489643D03*
X477284Y174586D03*
X473084D03*
Y170386D03*
X477284D03*
X498395Y174685D03*
Y170485D03*
X492911Y206602D03*
X488711D03*
X492911Y210802D03*
X488711D03*
X484511D03*
Y206602D03*
X480311Y210802D03*
Y206602D03*
X498052Y200389D03*
Y196189D03*
X477087Y201172D03*
X472887D03*
X477087Y196972D03*
X472887D03*
X519221Y165112D03*
X510821D03*
X506621D03*
X515021D03*
X502595Y174685D03*
Y170485D03*
X506135Y210557D03*
X510335D03*
X514535D03*
X518735D03*
X506135Y206357D03*
X510335D03*
X514535D03*
X518735D03*
X502252Y200389D03*
Y196189D03*
X497398Y226936D03*
X477398D03*
X520898Y228436D03*
X497398Y246936D03*
X477398D03*
Y266936D03*
X512500Y323000D03*
X492000Y321000D03*
X506500Y305500D03*
X520500Y331000D03*
X520381Y300757D03*
X495398Y338436D03*
X475398D03*
X495398Y358436D03*
Y378436D03*
X475398Y358436D03*
Y378436D03*
X477000Y418000D03*
X499000Y418500D03*
X485510Y442620D03*
X505510D03*
X519898Y465436D03*
X499898D03*
X479898D03*
X533619Y6482D03*
Y26482D03*
Y46482D03*
X550819Y6482D03*
Y26482D03*
Y46482D03*
X568019Y6482D03*
Y26482D03*
Y46482D03*
X573623Y66967D03*
X536419Y66482D03*
X556419D03*
X536419Y86482D03*
X556419D03*
X576419Y106482D03*
Y126482D03*
X536419D03*
X556419D03*
X536419Y106482D03*
X556419D03*
X544476Y161322D03*
X531876D03*
X536076D03*
X540276D03*
X536419Y146482D03*
X556419D03*
X544477Y210389D03*
X544476Y165522D03*
X536076D03*
X531876D03*
X540276D03*
X552924Y175124D03*
X548724D03*
Y170924D03*
X552924D03*
X527711Y175174D03*
X523511D03*
Y170974D03*
X527711D03*
X531877Y210389D03*
X536077D03*
X540277D03*
X531877Y206189D03*
X536077D03*
X540277D03*
X544477D03*
X527761Y200632D03*
X523561D03*
X527761Y196432D03*
X523561D03*
X553171Y200877D03*
X548971D03*
X553171Y196677D03*
X548971D03*
X546600Y257971D03*
X540898Y228436D03*
X561500Y232000D03*
X557000Y231500D03*
X560500Y268000D03*
X548417Y269770D03*
Y262970D03*
X549500Y305500D03*
X543900Y314000D03*
X559996Y282972D03*
X561500Y298000D03*
X534000Y282000D03*
X537136Y326402D03*
X525161Y311000D03*
X577500Y305000D03*
X524888Y330228D03*
X540736Y309902D03*
X537936Y322102D03*
X529000Y353500D03*
X526270Y338185D03*
X634119Y26482D03*
X585219Y46482D03*
Y26482D03*
Y6482D03*
X602419Y26482D03*
Y6482D03*
X619619D03*
Y26482D03*
Y46482D03*
X634119D03*
Y6482D03*
X602419Y46482D03*
X628500Y104000D03*
X626500Y78500D03*
X611253Y65701D03*
X584543Y86671D03*
X611398Y86936D03*
X633753Y65701D03*
X633898Y86936D03*
X623500Y71500D03*
X634000Y123500D03*
X607000D03*
X616000Y138000D03*
Y115500D03*
X594500Y117000D03*
X616000Y173500D03*
X615500Y199000D03*
X615898Y244436D03*
Y224436D03*
X615398Y266436D03*
X587500Y318500D03*
X600000Y298500D03*
X616498Y316236D03*
X615398Y284436D03*
X633398Y325436D03*
X622598Y331736D03*
X630000Y345500D03*
X600000Y337500D03*
Y342000D03*
X595500D03*
Y337500D03*
X630000Y387500D03*
X612798Y413000D03*
X610898Y425436D03*
Y445436D03*
X617798Y413000D03*
X632898Y404936D03*
Y444936D03*
Y424936D03*
X624898Y400936D03*
X610898Y465436D03*
X632898Y464936D03*
G54D40*
X596102Y66929D03*
X602008Y74803D03*
X596102Y82677D03*
G54D23*
X43072Y369247D03*
X43159Y377285D03*
X55352Y390774D03*
X60052Y390692D03*
X51094Y390725D03*
X538000Y296700D03*
X583000Y80200D03*
G54D14*
X-26505Y124122D03*
Y133422D03*
Y142722D03*
Y204122D03*
Y213422D03*
Y164122D03*
Y173422D03*
Y182722D03*
Y244122D03*
Y253422D03*
Y262722D03*
Y222722D03*
Y283072D03*
G54D32*
X66091Y365163D03*
X577707Y66918D03*
X522800Y322000D03*
X530136Y334902D03*
G54D41*
X618566Y343800D03*
X607104D03*
Y387500D03*
X618566D03*
G54D42*
G01X-4246Y-109426D02*
Y-189426D01*
G01D02*
X1290354D01*
G01X-4246Y-144926D02*
X1290354D01*
G01X-8246Y-93426D02*
G02I-12000J0D01*
G01X-13396D02*
G02I-6850J0D01*
G01X-20246Y-109426D02*
Y-77426D01*
G01X-4246Y-93426D02*
X-36246D01*
G01X-4246Y-109426D02*
X1290354D01*
G01X48325Y352400D02*
Y348514D01*
G01X52705Y352345D02*
Y348626D01*
G01X57398Y352410D02*
Y348682D01*
G01X37500Y386500D02*
X38513Y387513D01*
X41309D01*
G01X45807Y387868D02*
X48858Y384817D01*
G01X41309Y387513D02*
X45452D01*
X45807Y387868D01*
G01X51094Y390775D02*
Y394478D01*
G01X55352Y390824D02*
Y394674D01*
G01X60052Y390742D02*
Y394674D01*
G01X502854Y-109426D02*
Y-189426D01*
G01X520500Y331000D02*
Y329000D01*
X522750Y326750D01*
Y326000D01*
G01X570709Y157637D02*
Y161889D01*
G01D02*
X574961D01*
G01X566457D02*
X570709D01*
G01D02*
Y166141D01*
G01X576457Y161889D02*
X580709D01*
G01X570709Y191889D02*
X574961D01*
G01X566457D02*
X570709D01*
G01D02*
Y196141D01*
G01Y187637D02*
Y191889D01*
G01X576457D02*
X580709D01*
G01X570709Y181889D02*
X574961D01*
G01X566457D02*
X570709D01*
G01D02*
Y186141D01*
G01Y177637D02*
Y181889D01*
G01X576457D02*
X580709D01*
G01X570709Y171889D02*
X574961D01*
G01X566457D02*
X570709D01*
G01D02*
Y176141D01*
G01Y167637D02*
Y171889D01*
G01X576457D02*
X580709D01*
G01X542500Y257971D02*
X546600D01*
G01X543900Y314000D02*
X544000D01*
Y307000D01*
X538000Y301000D01*
Y296750D01*
G01X533686Y326402D02*
X537136D01*
G01X580709Y157637D02*
Y161889D01*
G01X590709Y157637D02*
Y161889D01*
G01X600709Y157637D02*
Y161889D01*
G01X580709D02*
X584961D01*
G01X580709D02*
Y166141D01*
G01Y191889D02*
X584961D01*
G01X580709D02*
Y196141D01*
G01Y187637D02*
Y191889D01*
G01Y181889D02*
X584961D01*
G01X580709D02*
Y186141D01*
G01Y177637D02*
Y181889D01*
G01Y171889D02*
X584961D01*
G01X580709D02*
Y176141D01*
G01Y167637D02*
Y171889D01*
G01X590709Y161889D02*
X594961D01*
G01X586457D02*
X590709D01*
G01D02*
Y166141D01*
G01X600709Y161889D02*
X604961D01*
G01X596457D02*
X600709D01*
G01D02*
Y166141D01*
G01X590709Y191889D02*
X594961D01*
G01X586457D02*
X590709D01*
G01D02*
Y196141D01*
G01Y187637D02*
Y191889D01*
G01X600709D02*
X604961D01*
G01X596457D02*
X600709D01*
G01D02*
Y196141D01*
G01Y187637D02*
Y191889D01*
G01X590709Y181889D02*
X594961D01*
G01X586457D02*
X590709D01*
G01D02*
Y186141D01*
G01Y177637D02*
Y181889D01*
G01X600709D02*
X604961D01*
G01X596457D02*
X600709D01*
G01D02*
Y186141D01*
G01Y177637D02*
Y181889D01*
G01X590709Y171889D02*
X594961D01*
G01X586457D02*
X590709D01*
G01D02*
Y176141D01*
G01Y167637D02*
Y171889D01*
G01X600709D02*
X604961D01*
G01X596457D02*
X600709D01*
G01D02*
Y176141D01*
G01Y167637D02*
Y171889D01*
G01X640354Y-109426D02*
Y-189426D01*
G01X755354Y-109426D02*
Y-189426D01*
G01X922854Y-109426D02*
Y-189426D01*
G01X1092854Y-109426D02*
Y-189426D01*
G01X1290354Y-109426D02*
Y-189426D01*
G01X1318354Y-93426D02*
G02I-12000J0D01*
G01X1313204D02*
G02I-6850J0D01*
G01X1306354Y-109426D02*
Y-77426D01*
G01X1322354Y-93426D02*
X1290354D01*
G54D15*
X-25005Y173422D03*
Y133422D03*
Y213422D03*
Y253422D03*
G54D33*
X69491Y365163D03*
X526200Y322000D03*
X533536Y334902D03*
X581107Y66918D03*
G54D24*
X57398Y355860D03*
X48325Y355850D03*
X52705Y355795D03*
G54D43*
G01X-27555Y302202D02*
X-12610D01*
G01X-27555Y327202D02*
X-7102D01*
G01X-6602Y357202D02*
X-27555D01*
G01X525161Y315852D02*
Y311000D01*
G01X617798Y408936D02*
Y413000D01*
G01X612798Y408836D02*
Y413000D01*
G54D16*
X197Y189819D03*
Y197419D03*
X9297Y189819D03*
Y197419D03*
X472898Y182636D03*
Y190236D03*
X550498Y322336D03*
Y329936D03*
G54D25*
X57398Y352460D03*
X48325Y352450D03*
X52705Y352395D03*
G54D34*
X67408Y391259D03*
G54D44*
G01X-12610Y302202D02*
X-8481D01*
X2334Y313017D01*
Y318654D01*
G54D35*
X475061Y23622D03*
X565612Y448818D03*
G54D17*
X-25005Y283072D03*
G54D26*
X45807Y388068D03*
X38128Y374332D03*
X542500Y269171D03*
X634488Y72003D03*
G54D45*
G01X48858Y384817D02*
X49902Y383773D01*
Y379652D01*
G54D27*
X38109Y363133D03*
X542500Y258171D03*
X618000Y71700D03*
X612798Y403036D03*
X617798Y403136D03*
G54D18*
X-27555Y332202D03*
Y327202D03*
Y322202D03*
Y317202D03*
Y312202D03*
Y307202D03*
Y302202D03*
Y357202D03*
Y352202D03*
Y347202D03*
Y342202D03*
Y337202D03*
G54D36*
X462000Y192300D03*
Y180700D03*
X448500Y192300D03*
Y180700D03*
X435000Y192300D03*
Y180700D03*
X421500Y192300D03*
Y180700D03*
G54D46*
G01X57582Y363352D02*
Y360163D01*
X58809Y358936D01*
X61898D01*
G54D37*
X512989Y198162D03*
Y173362D03*
X487625Y198086D03*
Y173286D03*
X538135Y198177D03*
Y173377D03*
G54D19*
X49902Y379652D03*
X52462D03*
X55022D03*
X57582D03*
Y363352D03*
X55022D03*
X52462D03*
X49902D03*
G54D28*
X38109Y368733D03*
X542500Y263771D03*
X618000Y77300D03*
X612798Y408636D03*
X617798Y408736D03*
G54D47*
G01X16751Y-179426D02*
Y-161926D01*
G01X25047D02*
X16751Y-172718D01*
G01X26357Y-179426D02*
X20462Y-167760D01*
G01X34032Y-179426D02*
Y-161926D01*
X44076Y-179426D01*
Y-161926D01*
G01X56554Y-179426D02*
X54807Y-179134D01*
X53279Y-177968D01*
X51969Y-176218D01*
X51095Y-174176D01*
X50659Y-171843D01*
Y-169509D01*
X51095Y-167176D01*
X51969Y-165134D01*
X53279Y-163385D01*
X54807Y-162218D01*
X56554Y-161926D01*
X58300Y-162218D01*
X59829Y-163385D01*
X61139Y-165134D01*
X62013Y-167176D01*
X62449Y-169509D01*
Y-171843D01*
X62013Y-174176D01*
X61139Y-176218D01*
X59829Y-177968D01*
X58300Y-179134D01*
X56554Y-179426D01*
G01X69469D02*
X78639Y-161926D01*
G01X69469D02*
X78639Y-179426D01*
G01X104687D02*
Y-161926D01*
X109927D01*
X111674Y-162801D01*
X112984Y-164843D01*
X113421Y-167176D01*
X112984Y-169509D01*
X111892Y-171259D01*
X109927Y-172135D01*
X104687D01*
G01X126554Y-179426D02*
X124807Y-179134D01*
X123279Y-177968D01*
X121969Y-176218D01*
X121095Y-174176D01*
X120659Y-171843D01*
Y-169509D01*
X121095Y-167176D01*
X121969Y-165134D01*
X123279Y-163385D01*
X124807Y-162218D01*
X126554Y-161926D01*
X128300Y-162218D01*
X129829Y-163385D01*
X131139Y-165134D01*
X132013Y-167176D01*
X132449Y-169509D01*
Y-171843D01*
X132013Y-174176D01*
X131139Y-176218D01*
X129829Y-177968D01*
X128300Y-179134D01*
X126554Y-179426D01*
G01X137504Y-161926D02*
X140560Y-179426D01*
X144054Y-161926D01*
X147547Y-179426D01*
X150604Y-161926D01*
G01X165921Y-179426D02*
X157187D01*
Y-161926D01*
X165921D01*
G01X162427Y-170384D02*
X157187D01*
G01X174687Y-179426D02*
Y-161926D01*
X180146D01*
X181892Y-162801D01*
X182984Y-163968D01*
X183421Y-166301D01*
X182984Y-168635D01*
X181674Y-170093D01*
X180146Y-170968D01*
X174687D01*
G01X180146D02*
X183421Y-179426D01*
G01X214054Y-161926D02*
Y-179426D01*
G01X209032Y-161926D02*
X219076D01*
G01X227187Y-179426D02*
Y-161926D01*
X232646D01*
X234392Y-162801D01*
X235484Y-163968D01*
X235921Y-166301D01*
X235484Y-168635D01*
X234174Y-170093D01*
X232646Y-170968D01*
X227187D01*
G01X232646D02*
X235921Y-179426D01*
G01X243595D02*
X249054Y-161926D01*
X254513Y-179426D01*
G01X252547Y-173301D02*
X245560D01*
G01X261532Y-179426D02*
Y-161926D01*
X271576Y-179426D01*
Y-161926D01*
G01X279469Y-177093D02*
X281216Y-178551D01*
X283181Y-179426D01*
X284927D01*
X286674Y-178551D01*
X287984Y-177093D01*
X288639Y-175051D01*
X288202Y-173010D01*
X287111Y-171259D01*
X285146Y-170093D01*
X282526Y-169509D01*
X280997Y-168343D01*
X280342Y-166301D01*
X280779Y-164259D01*
X281871Y-162801D01*
X283399Y-161926D01*
X284927D01*
X286456Y-162509D01*
X287766Y-163968D01*
G01X298934Y-161926D02*
X304174D01*
G01X301554D02*
Y-179426D01*
G01X298934D02*
X304174D01*
G01X319054Y-161926D02*
Y-179426D01*
G01X314032Y-161926D02*
X324076D01*
G01X333934D02*
X339174D01*
G01X336554D02*
Y-179426D01*
G01X333934D02*
X339174D01*
G01X354054D02*
X352307Y-179134D01*
X350779Y-177968D01*
X349469Y-176218D01*
X348595Y-174176D01*
X348159Y-171843D01*
Y-169509D01*
X348595Y-167176D01*
X349469Y-165134D01*
X350779Y-163385D01*
X352307Y-162218D01*
X354054Y-161926D01*
X355800Y-162218D01*
X357329Y-163385D01*
X358639Y-165134D01*
X359513Y-167176D01*
X359949Y-169509D01*
Y-171843D01*
X359513Y-174176D01*
X358639Y-176218D01*
X357329Y-177968D01*
X355800Y-179134D01*
X354054Y-179426D01*
G01X366532D02*
Y-161926D01*
X376576Y-179426D01*
Y-161926D01*
G01X408300Y-170093D02*
X409174Y-169218D01*
X409829Y-167760D01*
X410266Y-165717D01*
X409829Y-163968D01*
X408956Y-162801D01*
X407427Y-161926D01*
X401532D01*
Y-179426D01*
X408737D01*
X410266Y-178260D01*
X411139Y-176509D01*
X411576Y-174468D01*
X411139Y-172426D01*
X409829Y-170676D01*
X408300Y-170093D01*
X401532D01*
G01X424054Y-179426D02*
X422307Y-179134D01*
X420779Y-177968D01*
X419469Y-176218D01*
X418595Y-174176D01*
X418159Y-171843D01*
Y-169509D01*
X418595Y-167176D01*
X419469Y-165134D01*
X420779Y-163385D01*
X422307Y-162218D01*
X424054Y-161926D01*
X425800Y-162218D01*
X427329Y-163385D01*
X428639Y-165134D01*
X429513Y-167176D01*
X429949Y-169509D01*
Y-171843D01*
X429513Y-174176D01*
X428639Y-176218D01*
X427329Y-177968D01*
X425800Y-179134D01*
X424054Y-179426D01*
G01X436095D02*
X441554Y-161926D01*
X447013Y-179426D01*
G01X445047Y-173301D02*
X438060D01*
G01X454687Y-179426D02*
Y-161926D01*
X460146D01*
X461892Y-162801D01*
X462984Y-163968D01*
X463421Y-166301D01*
X462984Y-168635D01*
X461674Y-170093D01*
X460146Y-170968D01*
X454687D01*
G01X460146D02*
X463421Y-179426D01*
G01X471751D02*
Y-161926D01*
X476117D01*
X477864Y-162801D01*
X479174Y-163968D01*
X480266Y-165717D01*
X481139Y-167760D01*
X481357Y-170676D01*
X481139Y-173593D01*
X480266Y-175635D01*
X479174Y-177385D01*
X477864Y-178551D01*
X476117Y-179426D01*
X471751D01*
G01X208377Y-134426D02*
Y-116926D01*
X214054Y-131509D01*
X219731Y-116926D01*
Y-134426D01*
G01X231554D02*
X230244Y-134134D01*
X228934Y-132968D01*
X228060Y-130926D01*
X227624Y-128593D01*
X228060Y-126259D01*
X228934Y-124218D01*
X230244Y-123051D01*
X231554Y-122760D01*
X232864Y-123051D01*
X234174Y-124218D01*
X235047Y-126259D01*
X235266Y-128593D01*
X235047Y-130926D01*
X234174Y-132968D01*
X232864Y-134134D01*
X231554Y-134426D01*
G01X252984Y-116926D02*
Y-134426D01*
G01Y-131802D02*
X252111Y-133260D01*
X250800Y-134134D01*
X249272Y-134426D01*
X247526Y-133843D01*
X246216Y-132385D01*
X245342Y-130635D01*
X245124Y-128593D01*
X245342Y-126551D01*
X246216Y-124801D01*
X247526Y-123343D01*
X249272Y-122760D01*
X250800Y-123051D01*
X251892Y-123635D01*
X252984Y-124801D01*
G01X263279Y-126551D02*
X270266D01*
X269611Y-124509D01*
X268519Y-123343D01*
X266991Y-122760D01*
X265462Y-123051D01*
X264152Y-123926D01*
X263279Y-125968D01*
X262842Y-127718D01*
Y-129468D01*
X263279Y-131218D01*
X264371Y-132968D01*
X265681Y-134134D01*
X267209Y-134426D01*
X268737Y-133843D01*
X270266Y-132093D01*
G01X284054Y-134426D02*
Y-116926D01*
G01X536554Y-179426D02*
Y-161926D01*
X533934Y-165426D01*
G01Y-179426D02*
X539174D01*
G01X549906Y-164843D02*
X551216Y-163093D01*
X552744Y-162218D01*
X554491Y-161926D01*
X556674Y-162509D01*
X558202Y-163968D01*
X558639Y-165717D01*
X558421Y-167468D01*
X557547Y-168926D01*
X553181Y-171843D01*
X551216Y-173884D01*
X549906Y-176802D01*
X549469Y-179426D01*
X558639D01*
G01X566751Y-176802D02*
X568060Y-178260D01*
X569589Y-179134D01*
X571554Y-179426D01*
X573519Y-178843D01*
X575047Y-177676D01*
X576139Y-175635D01*
X576357Y-173301D01*
X575921Y-170968D01*
X574829Y-169509D01*
X573300Y-168343D01*
X571772Y-168051D01*
X570244Y-168343D01*
X568279Y-169509D01*
X568934Y-161926D01*
X574829D01*
G01X584906Y-164843D02*
X586216Y-163093D01*
X587744Y-162218D01*
X589491Y-161926D01*
X591674Y-162509D01*
X593202Y-163968D01*
X593639Y-165717D01*
X593421Y-167468D01*
X592547Y-168926D01*
X588181Y-171843D01*
X586216Y-173884D01*
X584906Y-176802D01*
X584469Y-179426D01*
X593639D01*
G01X601751Y-175926D02*
X603060Y-177968D01*
X604807Y-179134D01*
X606772Y-179426D01*
X608519Y-179134D01*
X610266Y-177676D01*
X611357Y-175926D01*
X611576Y-174176D01*
X611139Y-172135D01*
X609611Y-170676D01*
X608082Y-170093D01*
X606117D01*
G01X608082D02*
X609392Y-169218D01*
X610484Y-167760D01*
X610921Y-166010D01*
X610484Y-164259D01*
X609392Y-162801D01*
X607427Y-161926D01*
X605462Y-162218D01*
X603497Y-163385D01*
G01X523437Y-134426D02*
Y-116926D01*
X528677D01*
X530424Y-117801D01*
X531734Y-119843D01*
X532171Y-122176D01*
X531734Y-124509D01*
X530642Y-126259D01*
X528677Y-127135D01*
X523437D01*
G01X550107Y-118385D02*
X548797Y-117509D01*
X547269Y-116926D01*
X545522D01*
X543557Y-117801D01*
X542029Y-119259D01*
X540937Y-121010D01*
X540064Y-123926D01*
X539845Y-126551D01*
X540282Y-129176D01*
X540937Y-130926D01*
X542247Y-132676D01*
X543776Y-133843D01*
X545304Y-134426D01*
X546832D01*
X548361Y-133843D01*
X549671Y-132968D01*
X550763Y-131802D01*
G01X564550Y-125093D02*
X565424Y-124218D01*
X566079Y-122760D01*
X566516Y-120717D01*
X566079Y-118968D01*
X565206Y-117801D01*
X563677Y-116926D01*
X557782D01*
Y-134426D01*
X564987D01*
X566516Y-133260D01*
X567389Y-131509D01*
X567826Y-129468D01*
X567389Y-127426D01*
X566079Y-125676D01*
X564550Y-125093D01*
X557782D01*
G01X573754Y-140259D02*
X586854D01*
G01X592782Y-134426D02*
Y-116926D01*
X602826Y-134426D01*
Y-116926D01*
G01X615304Y-134426D02*
X613557Y-134134D01*
X612029Y-132968D01*
X610719Y-131218D01*
X609845Y-129176D01*
X609409Y-126843D01*
Y-124509D01*
X609845Y-122176D01*
X610719Y-120134D01*
X612029Y-118385D01*
X613557Y-117218D01*
X615304Y-116926D01*
X617050Y-117218D01*
X618579Y-118385D01*
X619889Y-120134D01*
X620763Y-122176D01*
X621199Y-124509D01*
Y-126843D01*
X620763Y-129176D01*
X619889Y-131218D01*
X618579Y-132968D01*
X617050Y-134134D01*
X615304Y-134426D01*
G01X697854Y-179426D02*
Y-161926D01*
X695234Y-165426D01*
G01Y-179426D02*
X700474D01*
G01X666145Y-116926D02*
X671604Y-134426D01*
X677063Y-116926D01*
G01X693471Y-134426D02*
X684737D01*
Y-116926D01*
X693471D01*
G01X689977Y-125384D02*
X684737D01*
G01X702237Y-134426D02*
Y-116926D01*
X707696D01*
X709442Y-117801D01*
X710534Y-118968D01*
X710971Y-121301D01*
X710534Y-123635D01*
X709224Y-125093D01*
X707696Y-125968D01*
X702237D01*
G01X707696D02*
X710971Y-134426D01*
G01X724104Y-135009D02*
X723667Y-134718D01*
Y-134134D01*
X724104Y-133843D01*
X724541Y-134134D01*
Y-134718D01*
X724104Y-135009D01*
G01X790937Y-116926D02*
Y-134426D01*
X799671D01*
G01X816734D02*
Y-122760D01*
G01Y-124801D02*
X815861Y-123635D01*
X814550Y-123051D01*
X813022Y-122760D01*
X811494Y-123343D01*
X810184Y-124509D01*
X809310Y-126259D01*
X808874Y-128593D01*
X809310Y-130926D01*
X810184Y-132676D01*
X811494Y-133843D01*
X813022Y-134426D01*
X814550Y-134134D01*
X815861Y-133260D01*
X816734Y-132093D01*
G01X825719Y-139676D02*
X827029Y-140259D01*
X828776Y-139676D01*
X829867Y-138510D01*
X830741Y-137051D01*
X832050Y-132385D01*
X834889Y-122760D01*
G01X827902D02*
X832050Y-132385D01*
G01X844529Y-126551D02*
X851516D01*
X850861Y-124509D01*
X849769Y-123343D01*
X848241Y-122760D01*
X846712Y-123051D01*
X845402Y-123926D01*
X844529Y-125968D01*
X844092Y-127718D01*
Y-129468D01*
X844529Y-131218D01*
X845621Y-132968D01*
X846931Y-134134D01*
X848459Y-134426D01*
X849987Y-133843D01*
X851516Y-132093D01*
G01X862247Y-134426D02*
Y-122760D01*
G01Y-125093D02*
X863339Y-123926D01*
X864431Y-123051D01*
X865959Y-122760D01*
X867050Y-123051D01*
X868361Y-123926D01*
G01X879529Y-132385D02*
X880621Y-133551D01*
X882149Y-134426D01*
X883459D01*
X884769Y-133843D01*
X885642Y-132968D01*
X886079Y-131802D01*
X885861Y-130051D01*
X884987Y-129176D01*
X881057Y-127426D01*
X880184Y-125384D01*
X880621Y-123926D01*
X881494Y-123051D01*
X882804Y-122760D01*
X884114Y-123051D01*
X885424Y-123926D01*
G01X825937Y-161926D02*
Y-179426D01*
X834671D01*
G01X847804D02*
Y-161926D01*
X845184Y-165426D01*
G01Y-179426D02*
X850424D01*
G01X924737Y-175926D02*
X925829Y-177676D01*
X927139Y-178843D01*
X928667Y-179426D01*
X930414Y-178843D01*
X931724Y-177676D01*
X933034Y-175926D01*
X933471Y-173593D01*
Y-161926D01*
G01X946604Y-179426D02*
X944857Y-179134D01*
X943329Y-177968D01*
X942019Y-176218D01*
X941145Y-174176D01*
X940709Y-171843D01*
Y-169509D01*
X941145Y-167176D01*
X942019Y-165134D01*
X943329Y-163385D01*
X944857Y-162218D01*
X946604Y-161926D01*
X948350Y-162218D01*
X949879Y-163385D01*
X951189Y-165134D01*
X952063Y-167176D01*
X952499Y-169509D01*
Y-171843D01*
X952063Y-174176D01*
X951189Y-176218D01*
X949879Y-177968D01*
X948350Y-179134D01*
X946604Y-179426D01*
G01X959519Y-177093D02*
X961266Y-178551D01*
X963231Y-179426D01*
X964977D01*
X966724Y-178551D01*
X968034Y-177093D01*
X968689Y-175051D01*
X968252Y-173010D01*
X967161Y-171259D01*
X965196Y-170093D01*
X962576Y-169509D01*
X961047Y-168343D01*
X960392Y-166301D01*
X960829Y-164259D01*
X961921Y-162801D01*
X963449Y-161926D01*
X964977D01*
X966506Y-162509D01*
X967816Y-163968D01*
G01X985971Y-179426D02*
X977237D01*
Y-161926D01*
X985971D01*
G01X982477Y-170384D02*
X977237D01*
G01X994737Y-179426D02*
Y-161926D01*
X999977D01*
X1001724Y-162801D01*
X1003034Y-164843D01*
X1003471Y-167176D01*
X1003034Y-169509D01*
X1001942Y-171259D01*
X999977Y-172135D01*
X994737D01*
G01X1012019Y-179426D02*
Y-161926D01*
G01X1021189D02*
Y-179426D01*
G01Y-170676D02*
X1012019D01*
G01X1047237Y-161926D02*
Y-179426D01*
X1055971D01*
G01X1063645D02*
X1069104Y-161926D01*
X1074563Y-179426D01*
G01X1072597Y-173301D02*
X1065610D01*
G01X1081801Y-161926D02*
Y-174468D01*
X1082674Y-177093D01*
X1084421Y-178843D01*
X1086604Y-179426D01*
X1088787Y-178843D01*
X1090534Y-177093D01*
X1091407Y-174468D01*
Y-161926D01*
G01X941801Y-134426D02*
Y-116926D01*
X946167D01*
X947914Y-117801D01*
X949224Y-118968D01*
X950316Y-120717D01*
X951189Y-122760D01*
X951407Y-125676D01*
X951189Y-128593D01*
X950316Y-130635D01*
X949224Y-132385D01*
X947914Y-133551D01*
X946167Y-134426D01*
X941801D01*
G01X960829Y-126551D02*
X967816D01*
X967161Y-124509D01*
X966069Y-123343D01*
X964541Y-122760D01*
X963012Y-123051D01*
X961702Y-123926D01*
X960829Y-125968D01*
X960392Y-127718D01*
Y-129468D01*
X960829Y-131218D01*
X961921Y-132968D01*
X963231Y-134134D01*
X964759Y-134426D01*
X966287Y-133843D01*
X967816Y-132093D01*
G01X978329Y-132385D02*
X979421Y-133551D01*
X980949Y-134426D01*
X982259D01*
X983569Y-133843D01*
X984442Y-132968D01*
X984879Y-131802D01*
X984661Y-130051D01*
X983787Y-129176D01*
X979857Y-127426D01*
X978984Y-125384D01*
X979421Y-123926D01*
X980294Y-123051D01*
X981604Y-122760D01*
X982914Y-123051D01*
X984224Y-123926D01*
G01X999104Y-122760D02*
Y-134426D01*
G01Y-118093D02*
X998667Y-117801D01*
Y-117218D01*
X999104Y-116926D01*
X999541Y-117218D01*
Y-117801D01*
X999104Y-118093D01*
G01X1013547Y-138801D02*
X1015076Y-139968D01*
X1016822Y-140259D01*
X1018350Y-139968D01*
X1019661Y-138510D01*
X1020534Y-136468D01*
Y-122760D01*
G01Y-125093D02*
X1019661Y-123926D01*
X1018350Y-123051D01*
X1016822Y-122760D01*
X1015076Y-123343D01*
X1013984Y-124509D01*
X1013110Y-126551D01*
X1012674Y-128593D01*
X1012892Y-130343D01*
X1013766Y-132385D01*
X1015076Y-133843D01*
X1016822Y-134426D01*
X1018132Y-134134D01*
X1019661Y-132968D01*
X1020534Y-131802D01*
G01X1030392Y-134426D02*
Y-122760D01*
G01Y-125676D02*
X1031266Y-124218D01*
X1032576Y-123051D01*
X1034322Y-122760D01*
X1035850Y-123051D01*
X1037161Y-124218D01*
X1037816Y-126259D01*
Y-134426D01*
G01X1048329Y-126551D02*
X1055316D01*
X1054661Y-124509D01*
X1053569Y-123343D01*
X1052041Y-122760D01*
X1050512Y-123051D01*
X1049202Y-123926D01*
X1048329Y-125968D01*
X1047892Y-127718D01*
Y-129468D01*
X1048329Y-131218D01*
X1049421Y-132968D01*
X1050731Y-134134D01*
X1052259Y-134426D01*
X1053787Y-133843D01*
X1055316Y-132093D01*
G01X1066047Y-134426D02*
Y-122760D01*
G01Y-125093D02*
X1067139Y-123926D01*
X1068231Y-123051D01*
X1069759Y-122760D01*
X1070850Y-123051D01*
X1072161Y-123926D01*
G01X1112804Y-179426D02*
Y-161926D01*
X1110184Y-165426D01*
G01Y-179426D02*
X1115424D01*
G01X1130304Y-161926D02*
X1128557Y-162509D01*
X1127247Y-163968D01*
X1126374Y-165717D01*
X1125719Y-168051D01*
X1125501Y-170676D01*
X1125719Y-173301D01*
X1126374Y-175635D01*
X1127247Y-177385D01*
X1128557Y-178843D01*
X1130304Y-179426D01*
X1132050Y-178843D01*
X1133361Y-177385D01*
X1134234Y-175635D01*
X1134889Y-173301D01*
X1135107Y-170676D01*
X1134889Y-168051D01*
X1134234Y-165717D01*
X1133361Y-163968D01*
X1132050Y-162509D01*
X1130304Y-161926D01*
G01X1143874Y-180009D02*
X1151734Y-161926D01*
G01X1165304Y-179426D02*
Y-161926D01*
X1162684Y-165426D01*
G01Y-179426D02*
X1167924D01*
G01X1179092Y-177385D02*
X1180621Y-178843D01*
X1182367Y-179426D01*
X1184114Y-178843D01*
X1185642Y-177093D01*
X1186734Y-174468D01*
X1187171Y-171843D01*
Y-168635D01*
X1186734Y-166010D01*
X1185642Y-163676D01*
X1184332Y-162509D01*
X1182804Y-161926D01*
X1181057Y-162509D01*
X1179747Y-163676D01*
X1178874Y-165426D01*
X1178437Y-167760D01*
X1178874Y-169801D01*
X1179966Y-171843D01*
X1181276Y-173010D01*
X1182804Y-173301D01*
X1184550Y-172718D01*
X1185861Y-171259D01*
X1187171Y-168635D01*
G01X1196374Y-180009D02*
X1204234Y-161926D01*
G01X1213656Y-164843D02*
X1214966Y-163093D01*
X1216494Y-162218D01*
X1218241Y-161926D01*
X1220424Y-162509D01*
X1221952Y-163968D01*
X1222389Y-165717D01*
X1222171Y-167468D01*
X1221297Y-168926D01*
X1216931Y-171843D01*
X1214966Y-173884D01*
X1213656Y-176802D01*
X1213219Y-179426D01*
X1222389D01*
G01X1235304Y-161926D02*
X1233557Y-162509D01*
X1232247Y-163968D01*
X1231374Y-165717D01*
X1230719Y-168051D01*
X1230501Y-170676D01*
X1230719Y-173301D01*
X1231374Y-175635D01*
X1232247Y-177385D01*
X1233557Y-178843D01*
X1235304Y-179426D01*
X1237050Y-178843D01*
X1238361Y-177385D01*
X1239234Y-175635D01*
X1239889Y-173301D01*
X1240107Y-170676D01*
X1239889Y-168051D01*
X1239234Y-165717D01*
X1238361Y-163968D01*
X1237050Y-162509D01*
X1235304Y-161926D01*
G01X1252804Y-179426D02*
Y-161926D01*
X1250184Y-165426D01*
G01Y-179426D02*
X1255424D01*
G01X1266156Y-164843D02*
X1267466Y-163093D01*
X1268994Y-162218D01*
X1270741Y-161926D01*
X1272924Y-162509D01*
X1274452Y-163968D01*
X1274889Y-165717D01*
X1274671Y-167468D01*
X1273797Y-168926D01*
X1269431Y-171843D01*
X1267466Y-173884D01*
X1266156Y-176802D01*
X1265719Y-179426D01*
X1274889D01*
G01X1160501Y-134426D02*
Y-116926D01*
X1164867D01*
X1166614Y-117801D01*
X1167924Y-118968D01*
X1169016Y-120717D01*
X1169889Y-122760D01*
X1170107Y-125676D01*
X1169889Y-128593D01*
X1169016Y-130635D01*
X1167924Y-132385D01*
X1166614Y-133551D01*
X1164867Y-134426D01*
X1160501D01*
G01X1186734D02*
Y-122760D01*
G01Y-124801D02*
X1185861Y-123635D01*
X1184550Y-123051D01*
X1183022Y-122760D01*
X1181494Y-123343D01*
X1180184Y-124509D01*
X1179310Y-126259D01*
X1178874Y-128593D01*
X1179310Y-130926D01*
X1180184Y-132676D01*
X1181494Y-133843D01*
X1183022Y-134426D01*
X1184550Y-134134D01*
X1185861Y-133260D01*
X1186734Y-132093D01*
G01X1200304Y-116926D02*
Y-134426D01*
G01X1197247Y-122760D02*
X1203361D01*
G01X1214529Y-126551D02*
X1221516D01*
X1220861Y-124509D01*
X1219769Y-123343D01*
X1218241Y-122760D01*
X1216712Y-123051D01*
X1215402Y-123926D01*
X1214529Y-125968D01*
X1214092Y-127718D01*
Y-129468D01*
X1214529Y-131218D01*
X1215621Y-132968D01*
X1216931Y-134134D01*
X1218459Y-134426D01*
X1219987Y-133843D01*
X1221516Y-132093D01*
G54D29*
X38128Y379932D03*
X45807Y393668D03*
X542500Y274771D03*
X634488Y77603D03*
G54D38*
X570709Y161889D03*
X580709D03*
X570709Y214409D03*
X580709D03*
X570709Y204409D03*
X580709D03*
X570709Y191889D03*
X580709D03*
X570709Y181889D03*
X580709D03*
X570709Y171889D03*
X580709D03*
X570709Y244409D03*
X580709D03*
X570709Y276929D03*
X580709D03*
X570709Y266929D03*
X580709D03*
X570709Y256929D03*
X580709D03*
X570709Y234409D03*
X580709D03*
X570709Y224409D03*
X580709D03*
X570709Y286929D03*
X580709D03*
X590709Y161889D03*
X600709D03*
X590709Y214409D03*
X600709D03*
X590709Y204409D03*
X600709D03*
X590709Y191889D03*
X600709D03*
X590709Y181889D03*
X600709D03*
X590709Y171889D03*
X600709D03*
X590709Y244409D03*
X600709D03*
X590709Y276929D03*
X600709D03*
X590709Y266929D03*
X600709D03*
X590709Y256929D03*
X600709D03*
X590709Y234409D03*
X600709D03*
X590709Y224409D03*
X600709D03*
X590709Y286929D03*
X600709D03*
G54D48*
G01X-27555Y317202D02*
X-15223D01*
X-10295Y322130D01*
X3773D01*
X10467Y315436D01*
X97097D01*
X112664Y299869D01*
X463259D01*
G01X-27555Y322202D02*
X-12698D01*
X-11020Y323880D01*
X4498D01*
X11192Y317186D01*
X96373D01*
X96374Y317187D01*
X97822D01*
X112965Y302044D01*
X196289D01*
G01X3398Y326936D02*
X3917D01*
X11917Y318936D01*
X95648D01*
X95649Y318937D01*
X98547D01*
X113265Y304219D01*
X135063D01*
G01X-27555Y342202D02*
X-15500D01*
X-13822Y340524D01*
X-5477D01*
X1547Y333500D01*
X4862D01*
X14176Y324186D01*
X93473D01*
X93474Y324187D01*
X100723D01*
X101749Y323161D01*
Y323160D01*
X114165Y310744D01*
X310990D01*
G01X-27555Y337202D02*
X-13702D01*
X-10500Y334000D01*
X-1429D01*
X1071Y331500D01*
X4386D01*
X13450Y322436D01*
X94198D01*
X94199Y322437D01*
X99997D01*
X113865Y308569D01*
X439407D01*
G01X-27555Y332202D02*
X-2107D01*
X595Y329500D01*
X3911D01*
X12725Y320686D01*
X94923D01*
X94924Y320687D01*
X99272D01*
X113565Y306394D01*
X401561D01*
G01X-27555Y347202D02*
X-16500D01*
X-11572Y342274D01*
X-4751D01*
X2023Y335500D01*
X9577D01*
X17391Y327686D01*
X92023D01*
X92024Y327687D01*
X102173D01*
X114766Y315094D01*
X228716D01*
G01X-27555Y352202D02*
X-16000D01*
X-7822Y344024D01*
X-4024D01*
X2500Y337500D01*
X10053D01*
X18117Y329436D01*
X91298D01*
X91299Y329437D01*
X102898D01*
X115066Y317269D01*
X264680D01*
G01X30058Y374132D02*
X27426D01*
X20057Y366763D01*
Y362268D01*
X1494Y343705D01*
G01X30058Y368932D02*
X26052D01*
X23386Y366266D01*
Y361397D01*
X5694Y343705D01*
G01X10000Y332000D02*
X16064Y325936D01*
X92748D01*
X92749Y325937D01*
X101448D01*
X103499Y323886D01*
Y323885D01*
X114465Y312919D01*
X358093D01*
G01X35148Y333436D02*
X28952D01*
X26723Y335665D01*
G01X35148Y337936D02*
X33194D01*
X30923Y335665D01*
G01X49902Y363352D02*
Y357477D01*
X48325Y355900D01*
G01D02*
X45263D01*
X43038Y353675D01*
G01X57582Y379652D02*
Y384772D01*
X60052Y387242D01*
G01D02*
X63391D01*
X67408Y391259D01*
G01X28182Y364061D02*
X30227D01*
X33558Y367392D01*
Y368932D01*
G01X66048Y369470D02*
X65034Y370484D01*
X44259D01*
X43072Y369297D01*
G01D02*
X41933Y370436D01*
X39612D01*
X38109Y368933D01*
G01D02*
X33559D01*
X33558Y368932D01*
G01X66097Y373979D02*
X64842Y372724D01*
X44270D01*
X43159Y373835D01*
G01X33558Y374132D02*
X38128D01*
G01X33558D02*
Y375672D01*
X30227Y379003D01*
X28182D01*
G01X38128Y374132D02*
X39774Y372486D01*
X41810D01*
X43159Y373835D01*
G01X38648Y333436D02*
X43898D01*
X44691Y332643D01*
X112180D01*
X125379Y319444D01*
X176762D01*
G01X38648Y337936D02*
X41876D01*
X45419Y334393D01*
X112905D01*
X125679Y321619D01*
X439585D01*
G01X43072Y360525D02*
Y365797D01*
G01D02*
X45320Y368045D01*
X51447D01*
X52462Y367030D01*
Y363352D01*
G01X52705Y355845D02*
Y358444D01*
X52462Y358687D01*
Y363352D01*
G01X66041Y365163D02*
X63405Y367799D01*
X55816D01*
X55022Y367005D01*
Y363352D01*
G01X57398Y355910D02*
X55022Y358286D01*
Y363352D01*
G01X43159Y382607D02*
Y377335D01*
G01D02*
X45279Y375215D01*
X51826D01*
X52462Y375851D01*
Y379652D01*
G01X51094Y387275D02*
X52462Y385907D01*
Y379652D01*
G01X66100Y378236D02*
X62804Y374940D01*
X55701D01*
X55022Y375619D01*
Y379652D01*
G01X55352Y387324D02*
Y385741D01*
X55022Y385411D01*
Y379652D01*
G01X534283Y263971D02*
X532995Y265259D01*
X530953D01*
X471326Y324886D01*
X137980D01*
X93395Y369471D01*
X74803D01*
G01D02*
X69549D01*
X69548Y369470D01*
G01D02*
Y365170D01*
X69541Y365163D01*
G01X81000Y372786D02*
X70790D01*
X69597Y373979D01*
G01D02*
Y378233D01*
X69600Y378236D01*
G01X534283Y268971D02*
X532621Y267309D01*
X531803D01*
X472176Y326936D01*
X138830D01*
X92980Y372786D01*
X81000D01*
G01X66041Y359891D02*
Y365163D01*
G01X66100Y383508D02*
Y378236D01*
G01X135063Y304219D02*
X467673D01*
X536401Y235491D01*
X539493D01*
X539494Y235490D01*
X562010D01*
X565000Y232500D01*
Y210118D01*
X570709Y204409D01*
G01X590709Y214409D02*
X596500Y220200D01*
Y258000D01*
X593250Y261250D01*
X567000D01*
X556846Y251096D01*
X538121D01*
X469773Y319444D01*
X176762D01*
G01X590709Y234409D02*
X586000Y239118D01*
Y249000D01*
X583750Y251250D01*
X565225D01*
X558216Y244241D01*
X540026D01*
X469173Y315094D01*
X228716D01*
G01X561500Y232000D02*
X559760Y233740D01*
X538769D01*
X538768Y233741D01*
X535676D01*
X467373Y302044D01*
X196289D01*
G01X580709Y224409D02*
X585300Y229000D01*
X591500D01*
X594750Y232250D01*
Y250250D01*
X592000Y253000D01*
X564500D01*
X557491Y245991D01*
X540751D01*
X469473Y317269D01*
X264680D01*
G01X570709Y214409D02*
X575000Y218700D01*
Y228500D01*
X576084Y229584D01*
Y238416D01*
X573759Y240741D01*
X573234D01*
X573233Y240742D01*
X571785D01*
X571784Y240741D01*
X538576D01*
X468573Y310744D01*
X310990D01*
G01X570709Y244409D02*
X562409D01*
X560491Y242491D01*
X539301D01*
X468873Y312919D01*
X358093D01*
G01X570709Y234409D02*
X567877Y237241D01*
X537126D01*
X467973Y306394D01*
X401561D01*
G01X557000Y231500D02*
X556510Y231990D01*
X534952D01*
X467073Y299869D01*
X463259D01*
G01X570709Y224409D02*
Y226684D01*
X574334Y230309D01*
Y237166D01*
X572509Y238991D01*
X537851D01*
X468273Y308569D01*
X439407D01*
G01X439585Y321619D02*
X470073D01*
X538846Y252846D01*
X555346D01*
X565500Y263000D01*
X602000D01*
X604500Y260500D01*
Y248200D01*
X600709Y244409D01*
G01X570709D02*
X573591D01*
X579000Y239000D01*
X583500D01*
X585500Y237000D01*
Y232000D01*
X584000Y230500D01*
X580000D01*
X577000Y227500D01*
Y217500D01*
X575500Y216000D01*
Y202500D01*
X577500Y200500D01*
X607650D01*
X611150Y204000D01*
Y287850D01*
X605743Y293257D01*
X537993D01*
G01X548417Y269770D02*
X554270D01*
X557500Y273000D01*
X604500D01*
X609100Y268400D01*
Y212800D01*
X600709Y204409D01*
G01Y224409D02*
X607050Y230750D01*
Y267450D01*
X603550Y270950D01*
X558450D01*
X550470Y262970D01*
X548417D01*
G01Y269770D02*
X543299D01*
X542500Y268971D01*
G01X548417Y262970D02*
X543501D01*
X542500Y263971D01*
G01X537783Y268971D02*
X542500D01*
G01X537783Y263971D02*
X542500D01*
G01X533686Y322102D02*
X532911Y321327D01*
Y315852D01*
G01X522750Y322000D02*
X522000Y321250D01*
Y308838D01*
X530081Y300757D01*
X532886D01*
G01X526250Y326000D02*
Y328866D01*
X524888Y330228D01*
G01X526250Y326000D02*
Y322000D01*
G01D02*
X529036Y319214D01*
Y308352D01*
G01X529011Y293257D02*
X537993D01*
G01D02*
X538000Y293250D01*
G01X533586Y330602D02*
X538336D01*
X540736Y328202D01*
Y309902D01*
G01X532886Y300757D02*
X540736Y308607D01*
Y309902D01*
G01X537936Y322102D02*
X533686D01*
G01X530186D02*
Y326402D01*
G01X530086Y334902D02*
Y330602D01*
G01D02*
Y328393D01*
X530186Y328293D01*
Y326402D01*
G01X526270Y338185D02*
X526803D01*
X530086Y334902D01*
G01X618000Y71500D02*
X623500D01*
G01X634488Y71803D02*
X628803D01*
X628500Y71500D01*
X623500D01*
G01X583000Y80250D02*
X583750Y79500D01*
X592925D01*
X596102Y82677D01*
G01X583000Y76750D02*
X600061D01*
X602008Y74803D01*
G01X581157Y66918D02*
X596091D01*
X596102Y66929D01*
G54D39*
X529011Y293257D03*
X532886Y300757D03*
X525136D03*
X529036Y308352D03*
X525161Y315852D03*
X532911D03*
M02*
